# S9S_MB_2U (Grand Teton) — schematic parts with pin connectivity, parts 1325–1486 of 6093; source: Cadence DE-HDL packaged netlist (pstxprt.dat, pstxnet.dat, pstchip.dat)

C2258  Q_CAP  0.1UF 25V 10% X7R  pkg 0402  page 212 : 1 = VFG3P3_CLK_GEN ; 2 = GND
C2259  Q_CAP  0.1UF 25V 10% X7R  pkg 0402  page 212 : 1 = VFG_3P3A_CLK_GEN ; 2 = GND
C2264  Q_CAP  1000PF 50V 5% EMPTY  pkg 0402  page 146 : 1 = GPU_3V3IO_RSVD0_FFU_ISO ; 2 = GND
C2265  Q_CAP  1000PF 50V 5% EMPTY  pkg 0402  page 146 : 1 = PRSNT_CABLE_GPU_B3_ISO_N ; 2 = GND
C2266  Q_CAP  1000PF 50V 5% EMPTY  pkg 0402  page 146 : 1 = GPU_3V3IO_RSVD1_FFU_ISO ; 2 = GND
C2267  Q_CAP  1000PF 50V 5% EMPTY  pkg 0402  page 146 : 1 = GPU_3V3IO_RSVD3_FFU_ISO ; 2 = GND
C2268  Q_CAP  1000PF 50V 5% EMPTY  pkg 0402  page 146 : 1 = GPU_3V3IO_RSVD5_FFU_ISO ; 2 = GND
C2269  Q_CAP  1000PF 50V 5% EMPTY  pkg 0402  page 146 : 1 = PRSNT_CABLE_GPU_A2_ISO_N ; 2 = GND
C2270  Q_CAP  1000PF 50V 5% EMPTY  pkg 0402  page 146 : 1 = PRSNT_CABLE_GPU_A1_ISO_N ; 2 = GND
C2271  Q_CAP  1000PF 50V 5% EMPTY  pkg 0402  page 145 : 1 = GPU_3V3IO_RSVD1_ISO ; 2 = GND
C2272  Q_CAP  1000PF 50V 5% EMPTY  pkg 0402  page 145 : 1 = GPU_3V3IO_RSVD4_ISO ; 2 = GND
C2273  Q_CAP  1000PF 50V 5% EMPTY  pkg 0402  page 145 : 1 = GPU_3V3IO_RSVD3_ISO ; 2 = GND
C2274  Q_CAP  0.1UF 25V 10% X7R  pkg 0402  page 170 : 1 = P3V3_AUX ; 2 = GND
C2275  Q_CAP  0.1UF 25V 10% X7R  pkg 0402  page 170 : 1 = P3V3_AUX ; 2 = GND
C2276  Q_CAP  0.1UF 25V 10% X7R  pkg 0402  page 170 : 1 = P3V3_AUX ; 2 = GND
C2283  Q_CAP  0.1UF 25V 10% X7R  pkg 0402  page 246 : 1 = P3V3_AUX ; 2 = GND
C2284  Q_CAP  22UF 16V 20% X6S  pkg C0805  page 169 : 1 = P3V3_AUX_USB_BUF ; 2 = GND
C2285  Q_CAP  0.1UF 25V 10% X7R  pkg 0402  page 169 : 1 = P3V3_AUX_USB_BUF ; 2 = GND
C2286  Q_CAP  0.1UF 25V 10% X7R  pkg 0402  page 169 : 1 = P3V3_AUX_USB_BUF ; 2 = GND
C2287  Q_CAP  0.01UF 50V 10% X7R  pkg C0402  page 263 : 1 = PWRGD_P1V8_PCH_AUX ; 2 = GND
C2289  Q_CAP  0.1UF 6.3V 10% X6S  pkg C0201  page 169 : 1 = USB3_PCH_TX_BUF_DP<4> ; 2 = USB3_PCH_TX_BUF_C_DP<4>
C2290  Q_CAP  0.1UF 6.3V 10% X6S  pkg C0201  page 169 : 1 = USB3_PCH_TX_BUF_DN<4> ; 2 = USB3_PCH_TX_BUF_C_DN<4>
C2291  Q_CAP  0.1UF 6.3V 10% X6S  pkg C0201  page 169 : 1 = USB3_PCH_RX_BUF_C_DP<4> ; 2 = USB3_PCH_RX_BUF_DP<4>
C2292  Q_CAP  0.1UF 6.3V 10% X6S  pkg C0201  page 169 : 1 = USB3_PCH_RX_BUF_C_DN<4> ; 2 = USB3_PCH_RX_BUF_DN<4>
C2293  Q_CAP  0.1UF 25V 10% EMPTY  pkg 0402  page 245 : 1 = RST_SMB_SWITCH_R_N ; 2 = GND
C2294  Q_CAP  0.1UF 25V 10% EMPTY  pkg 0402  page 245 : 1 = PDB_PRSNT_N ; 2 = GND
C2295  Q_CAP  0.1UF 25V 10% EMPTY  pkg 0402  page 245 : 1 = HPDB_HSC_PWRGD_R ; 2 = GND
C2296  Q_CAP  0.1UF 25V 10% EMPTY  pkg 0402  page 245 : 1 = FM_FAN_PWR_EN_R ; 2 = GND
C2297  Q_CAP  0.1UF 25V 10% EMPTY  pkg 0402  page 245 : 1 = FM_GPU_HSC_EN_BUF_R1 ; 2 = GND
C2313  Q_CAP  10UF 6.3V 20% EMPTY  pkg C0402  page 196 : 1 = P3V3_AUX_USB_HUB_2 ; 2 = GND
C2314  Q_CAP  0.1UF 25V 10% EMPTY  pkg 0402  page 196 : 1 = P3V3_AUX_USB_HUB_2 ; 2 = GND
C2315  Q_CAP  0.1UF 25V 10% EMPTY  pkg 0402  page 196 : 1 = P3V3_AUX_USB_HUB_2 ; 2 = GND
C2316  Q_CAP  1UF 25V 10% EMPTY  pkg C0402  page 196 : 1 = P3V3_AUX_USB_HUB_2 ; 2 = GND
C2317  Q_CAP  1UF 25V 10% EMPTY  pkg C0402  page 196 : 1 = RST_USB_HUB_2_R_N ; 2 = GND
C2318  Q_CAP  0.1UF 25V 10% EMPTY  pkg 0402  page 196 : 1 = P3V3_AUX_USB_HUB_2 ; 2 = GND
C2319  Q_CAP  0.1UF 25V 10% EMPTY  pkg 0402  page 196 : 1 = P3V3_AUX_USB_HUB_2 ; 2 = GND
C2320  Q_CAP  0.1UF 25V 10% EMPTY  pkg 0402  page 196 : 1 = P3V3_AUX_USB_HUB_2 ; 2 = GND
C2321  Q_CAP  0.1UF 25V 10% EMPTY  pkg 0402  page 196 : 1 = PD_USB_HUB_2_RSTN ; 2 = GND
C2322  Q_CAP  1UF 25V 10% EMPTY  pkg C0402  page 196 : 1 = P3V3_AUX_USB_HUB_2 ; 2 = GND
C2323  Q_CAP  1UF 25V 10% EMPTY  pkg C0402  page 196 : 1 = P3V3_AUX ; 2 = GND
C2324  Q_CAP  0.1UF 25V 10% EMPTY  pkg 0402  page 196 : 1 = P3V3_AUX ; 2 = GND
C2325  Q_CAP  0.1UF 25V 10% EMPTY  pkg 0402  page 196 : 1 = PD_USB_HUB_2_VREG ; 2 = GND
C2326  Q_CAP  12PF 50V 5% EMPTY  pkg C0402  page 196 : 1 = USB_HUB_2_XTAL_IN ; 2 = GND
C2327  Q_CAP  12PF 50V 5% EMPTY  pkg C0402  page 196 : 1 = USB_HUB_2_XTAL_OUT ; 2 = GND
C2328  Q_CAP  10UF 6.3V 20% X6S  pkg C0603  page 211 : 1 = P3V3_9ZXL045_VDD ; 2 = GND
C2329  Q_CAP  0.1UF 25V 10% X7R  pkg 0402  page 211 : 1 = P3V3_9ZXL045_VDD ; 2 = GND
C2330  Q_CAP  0.1UF 25V 10% X7R  pkg 0402  page 211 : 1 = P3V3_9ZXL045_VDD ; 2 = GND
C2331  Q_CAP  10UF 6.3V 20% X6S  pkg C0603  page 211 : 1 = P3V3_9ZXL045_VDDA ; 2 = GND
C2332  Q_CAP  10UF 6.3V 20% X6S  pkg C0603  page 211 : 1 = P3V3_9ZXL045_VDDR ; 2 = GND
C2333  Q_CAP  0.1UF 25V 10% X7R  pkg 0402  page 211 : 1 = P3V3_9ZXL045_VDD ; 2 = GND
C2334  Q_CAP  0.1UF 25V 10% X7R  pkg 0402  page 211 : 1 = P3V3_9ZXL045_VDDA ; 2 = GND
C2335  Q_CAP  0.1UF 25V 10% X7R  pkg 0402  page 211 : 1 = P3V3_9ZXL045_VDDR ; 2 = GND
C2336  Q_CAP  0.1UF 25V 10% X7R  pkg 0402  page 211 : 1 = P3V3_9ZXL045_VDD ; 2 = GND
C2337  Q_CAP  0.1UF 25V 10% X7R  pkg 0402  page 237 : 1 = P3V3_AUX ; 2 = GND
C2338  Q_CAP  0.1UF 25V 10% X7R  pkg 0402  page 237 : 1 = P3V3 ; 2 = GND
C2339  Q_CAP  0.1UF 25V 10% X7R  pkg 0402  page 211 : 1 = P3V3_9ZXL045_VDD ; 2 = GND
C2340  Q_CAP  1000PF 50V 5% EMPTY  pkg 0402  page 145 : 1 = HGX_DETECT_N_ISO ; 2 = GND
C2341  Q_CAP  0.1UF 25V 10% X7R  pkg 0402  page 145 : 1 = P3V3_AUX ; 2 = GND
C2342  Q_CAP  1000PF 50V 5% EMPTY  pkg 0402  page 246 : 1 = HPDB_HSC_PWRGD_ISO ; 2 = GND
C2343  Q_CAP  1000PF 50V 5% EMPTY  pkg 0402  page 146 : 1 = SWB_HSC_PWRGD_ISO ; 2 = GND
C2344  Q_CAP  0.1UF 25V 10% X7R  pkg 0402  page 155 : 1 = P3V3_AUX ; 2 = GND
C2345  Q_CAP  0.1UF 25V 10% X7R  pkg 0402  page 161 : 1 = P3V3_AUX ; 2 = GND
C2346  Q_CAP  0.1UF 25V 10% X7R  pkg 0402  page 158 : 1 = P3V3_AUX ; 2 = GND
C2347  Q_CAP  0.1UF 25V 10% X7R  pkg 0402  page 164 : 1 = P3V3_AUX ; 2 = GND
C2348  Q_CAP  0.1UF 25V 10% X7R  pkg 0402  page 248 : 1 = P3V3_AUX ; 2 = GND
C2349  Q_CAP_DIFFBUS  DIFF BUS_0.33UF 6.3V 10% X6S  pkg C0402  page 169 : 1 = USB3_PCH_RX_DP<4> ; 2 = USB3_PCH_RX_C_DP<4>
C2350  Q_CAP_DIFFBUS  DIFF BUS_0.33UF 6.3V 10% X6S  pkg C0402  page 169 : 1 = USB3_PCH_RX_DN<4> ; 2 = USB3_PCH_RX_C_DN<4>
C2351  Q_CAP  0.1UF 25V 10% EMPTY  pkg 0402  page 167 : 1 = P2E_MB_BMC_TX_BUF2_DP<0> ; 2 = P2E_MB_BMC_TX_BUF_C_DP<0>
C2352  Q_CAP  0.1UF 25V 10% EMPTY  pkg 0402  page 167 : 1 = P2E_MB_BMC_TX_BUF2_DN<0> ; 2 = P2E_MB_BMC_TX_BUF_C_DN<0>
C2353  Q_CAP  0.1UF 25V 10% EMPTY  pkg 0402  page 167 : 1 = P2E_MB_BMC_RX_BUF2_C_DP<0> ; 2 = P2E_MB_BMC_RX_BUF_DP<0>
C2354  Q_CAP  0.1UF 25V 10% EMPTY  pkg 0402  page 167 : 1 = P2E_MB_BMC_RX_BUF2_C_DN<0> ; 2 = P2E_MB_BMC_RX_BUF_DN<0>
C2355  Q_CAP  1UF 25V 10% X6S  pkg C0402  page 167 : 1 = P3V3_AUX ; 2 = GND
C2356  Q_CAP  10UF 16V 10% X6S  pkg C0805  page 167 : 1 = P3V3_AUX ; 2 = GND
C2357  Q_CAP  0.1UF 25V 10% X7R  pkg 0402  page 167 : 1 = P2E_BUF2_VDD ; 2 = GND
C2358  Q_CAP  0.1UF 25V 10% X7R  pkg 0402  page 167 : 1 = P2E_BUF2_VDD ; 2 = GND
C2359  Q_CAP  0.22UF 25V 10% X7R  pkg C0402  page 260 : 1 = PWRGD_P5V_ISO_R ; 2 = GND
C2360  Q_CAP  0.1UF 25V 10% X7R  pkg 0402  page 260 : 1 = P3V3 ; 2 = GND
C2363  Q_CAP  0.1UF 25V 10% EMPTY  pkg 0402  page 251 : 1 = HSC_TYPE_ADC ; 2 = GND
C2364  Q_CAP  0.1UF 25V 10% EMPTY  pkg 0402  page 251 : 1 = P3V3_AUX ; 2 = GND
C2369  Q_CAP  1UF 25V 10% EMPTY  pkg C0402  page 224 : 1 = FM_AC_PWR_BTN_R_N ; 2 = GND
C2370  Q_CAP  0.1UF 25V 10% EMPTY  pkg 0402  page 224 : 1 = P3V3_AUX ; 2 = GND
C2371  Q_CAP  0.1UF 25V 10% EMPTY  pkg 0402  page 245 : 1 = FM_AC_PWR_BTN_PDB_N ; 2 = GND
C2372  Q_CAP  1000PF 50V 5% EMPTY  pkg 0402  page 144 : 1 = PRSNT_SWB_ISO_N ; 2 = GND
C2373  Q_CAP  1000PF 50V 5% EMPTY  pkg 0402  page 144 : 1 = PRSNT_CABLE_SWB_B2_ISO_N ; 2 = GND
C2374  Q_CAP  1000PF 50V 5% EMPTY  pkg 0402  page 144 : 1 = PRSNT_CABLE_SWB_B1_ISO_N ; 2 = GND
C2376  Q_CAP  0.1UF 25V 10% X7R  pkg 0402  page 158 : 1 = P3V3_AUX ; 2 = GND
C2377  Q_CAP  0.1UF 25V 10% X7R  pkg 0402  page 164 : 1 = P3V3_AUX ; 2 = GND
C2378  Q_CAP  0.1UF 25V 10% X7R  pkg 0402  page 191 : 1 = P3V3_E1S_0 ; 2 = GND
C2379  Q_CAP  100NF 50V 10% EMPTY  pkg C0402  page 307 : 1 = UV_ADR_P2V5_COMP ; 2 = GND
C2380  Q_CAP  100NF 50V 10% EMPTY  pkg C0402  page 307 : 1 = UV_P2V5_COMP ; 2 = GND
C2381  Q_CAP  100NF 50V 10% EMPTY  pkg C0402  page 307 : 1 = P12V_AUX_UV_ADR_TRIGGER ; 2 = GND
C2382  Q_CAP  100NF 50V 10% EMPTY  pkg C0402  page 307 : 1 = P12V_AUX_UV_TRIGGER ; 2 = GND
C2383  Q_CAP  100NF 50V 10% EMPTY  pkg C0402  page 307 : 1 = P12V_AUX ; 2 = GND
C2384  Q_CAP  100NF 50V 10% EMPTY  pkg C0402  page 307 : 1 = P12V_AUX ; 2 = GND
C2385  Q_CAP  100NF 50V 10% EMPTY  pkg C0402  page 307 : 1 = DSW_PWROK_P2V5_COMP ; 2 = GND
C2386  Q_CAP  100NF 50V 10% EMPTY  pkg C0402  page 307 : 1 = PWRGD_DSW_PWROK_TRIGGER ; 2 = GND
C2387  Q_CAP  100NF 50V 10% EMPTY  pkg C0402  page 307 : 1 = P12V_AUX ; 2 = GND
C2388  Q_CAP  100NF 50V 10% EMPTY  pkg C0402  page 306 : 1 = OC_P2V5_COMP ; 2 = GND
C2389  Q_CAP  100NF 50V 10% EMPTY  pkg C0402  page 306 : 1 = HSC_OC_VOL ; 2 = GND
C2390  Q_CAP  100NF 50V 10% EMPTY  pkg C0402  page 306 : 1 = P12V_AUX ; 2 = GND
C2391  Q_CAP  1000PF 50V 5% EMPTY  pkg 0402  page 144 : 1 = PRSNT_CABLE_GPU_A3_ISO_N ; 2 = GND
C2392  Q_CAP  0.1UF 25V 10% EMPTY  pkg 0402  page 306 : 1 = U205_VDD ; 2 = GND
C2393  Q_CAP  0.1UF 25V 10% EMPTY  pkg 0402  page 306 : 1 = U369_VDD ; 2 = GND
C2394  Q_CAP  0.1UF 25V 10% X7R  pkg 0402  page 306 : 1 = U206_VDD ; 2 = GND
C2443  Q_CAP  10UF 6.3V 20% X6S  pkg C0402  page 278 : 1 = PVNN_TERM_CPU0 ; 2 = GND
C2444  Q_CAP  0.1UF 25V 10% X7R  pkg 0402  page 278 : 1 = PVNN_TERM_CPU0 ; 2 = GND
C2445  Q_CAP  1000PF 50V 5% EMPTY  pkg 0402  page 299 : 1 = FM_PVPP_HBM_CPU1_EN ; 2 = GND
C2446  Q_CAP  1000PF 50V 5% X7R  pkg 0402  page 284 : 1 = PVCCFA_EHV_FIVRA_CPU1_EN_R ; 2 = GND
C2447  Q_CAP  1000PF 50V 5% EMPTY  pkg 0402  page 284 : 1 = PWRGD_PVCCFA_EHV_FIVRA_CPU1_R ; 2 = GND
C2448  Q_CAP  10UF 4V 20% EMPTY  pkg C0603  page 284 : 1 = PVNN_TERM_CPU1 ; 2 = GND
C2449  Q_CAP  100NF 50V 10% X7R  pkg C0402  page 284 : 1 = PVNN_TERM_CPU1 ; 2 = GND
C2450  Q_CAP  1000PF 50V 5% EMPTY  pkg 0402  page 292 : 1 = PWRGD_PVCCINFAON_CPU1_R ; 2 = GND
C2451  Q_CAP  1000PF 50V 5% X7R  pkg 0402  page 292 : 1 = PVCCINFAON_CPU1_EN_R ; 2 = GND
C2452  Q_CAP  1000PF 50V 5% X7R  pkg 0402  page 292 : 1 = PVCCFA_EHV_CPU1_EN_R ; 2 = GND
C2453  Q_CAP  1000PF 50V 5% EMPTY  pkg 0402  page 292 : 1 = PWRGD_PVCCFA_EHV_CPU1_R ; 2 = GND
C2454  Q_CAP  1000PF 50V 5% EMPTY  pkg 0402  page 296 : 1 = PWRGD_PVCCD_HV_CPU1_R ; 2 = GND
C2458  Q_CAP  0.1UF 25V 10% EMPTY  pkg 0402  page 305 : 1 = P3V3_AUX ; 2 = GND
C2459  Q_CAP  1000PF 50V 10% EMPTY  pkg 0603  page 305 : 1 = P12V_HSC_TEMP_D+ ; 2 = P12V_HSC_TEMP_D-
C2460  Q_CAP  1000PF 50V 5% X7R  pkg 0402  page 299 : 1 = PWRGD_PVPP_HBM_CPU1_R ; 2 = GND
C2541  Q_CAP  0.22UF 25V 10% X7R  pkg C0402  page 259 : 1 = P3V3_AUX_EN ; 2 = GND
C2859  Q_CAP  1000PF 50V 5% EMPTY  pkg 0402  page 284 : 1 = PWRGD_PVCCIN_CPU1_R ; 2 = GND
C2860  Q_CAP  1000PF 50V 5% X7R  pkg 0402  page 284 : 1 = PVCCIN_CPU1_EN_R ; 2 = GND
C3266  Q_CAP  1000PF 50V 5% EMPTY  pkg 0402  page 266 : 1 = PWRGD_PVCCIN_CPU0_R ; 2 = GND
C3267  Q_CAP  1000PF 50V 5% X7R  pkg 0402  page 266 : 1 = PVCCIN_CPU0_EN_R ; 2 = GND
C3268  Q_CAP  1000PF 50V 5% X7R  pkg 0402  page 266 : 1 = PVCCFA_EHV_FIVRA_CPU0_EN_R ; 2 = GND
C3269  Q_CAP  1000PF 50V 5% EMPTY  pkg 0402  page 266 : 1 = PWRGD_PVCCFA_EHV_FIVRA_CPU0_R ; 2 = GND
C3270  Q_CAP  10UF 4V 20% EMPTY  pkg C0603  page 266 : 1 = PVNN_TERM_CPU0 ; 2 = GND
C3271  Q_CAP  100NF 50V 10% X7R  pkg C0402  page 266 : 1 = PVNN_TERM_CPU0 ; 2 = GND
C3273  Q_CAP  1000PF 50V 5% EMPTY  pkg 0402  page 274 : 1 = PWRGD_PVCCINFAON_CPU0_R ; 2 = GND
C3274  Q_CAP  1000PF 50V 5% X7R  pkg 0402  page 274 : 1 = PVCCINFAON_CPU0_EN_R ; 2 = GND
C3275  Q_CAP  1000PF 50V 5% X7R  pkg 0402  page 274 : 1 = PVCCFA_EHV_CPU0_EN_R ; 2 = GND
C3276  Q_CAP  1000PF 50V 5% EMPTY  pkg 0402  page 274 : 1 = PWRGD_PVCCFA_EHV_CPU0_R ; 2 = GND
C4562  Q_CAP  1UF 25V 10% EMPTY  pkg C0402  page 306 : 1 = U369_VDD ; 2 = GND
C5229  Q_CAP  1UF 25V 10% EMPTY  pkg C0402  page 152 : 1 = P3V3_AUX ; 2 = GND
C5232  Q_CAP  0.1UF 25V 10% EMPTY  pkg 0402  page 152 : 1 = PD_U5201_RSTN ; 2 = GND
C5234  Q_CAP  0.1UF 25V 10% EMPTY  pkg 0402  page 152 : 1 = P3V3_AUX ; 2 = GND
C5236  Q_CAP  0.1UF 25V 10% EMPTY  pkg 0402  page 152 : 1 = PD_U5201_VREG ; 2 = GND
D0  Q_LED  IC  pkg SMLF  page 218 : A = PU_PLD_HEARTBEAT_LVC3 ; C = FM_PLD_HEARTBEAT_LVC3_D
D6  Q_LED  IC  pkg SMLF  page 218 : A = LED_CPU_RMCA_CATERR ; C = GND
D7  BAT547F  IC  pkg SOT23_123XB  page 260 : 1 = P3V3 ; 3 = P5V
D42  SCHOTTKY_12  B0530WS7F IC  pkg SOD323XB  page 115 : 1 = PWRGD_FAIL_CPU0_AB_R1 ; 2 = P3V3_AUX
D43  SCHOTTKY_12  B0530WS7F IC  pkg SOD323XB  page 115 : 1 = PWRGD_FAIL_CPU0_CD_R1 ; 2 = P3V3_AUX
D44  SCHOTTKY_12  B0530WS7F IC  pkg SOD323XB  page 115 : 1 = PWRGD_FAIL_CPU0_EF_R1 ; 2 = P3V3_AUX
D45  SCHOTTKY_12  B0530WS7F IC  pkg SOD323XB  page 115 : 1 = PWRGD_FAIL_CPU0_GH_R1 ; 2 = P3V3_AUX
D46  SCHOTTKY_12  B0530WS7F IC  pkg SOD323XB  page 115 : 1 = PWRGD_FAIL_CPU1_AB_R1 ; 2 = P3V3_AUX
D47  SCHOTTKY_12  B0530WS7F IC  pkg SOD323XB  page 115 : 1 = PWRGD_FAIL_CPU1_CD_R1 ; 2 = P3V3_AUX
D48  SCHOTTKY_12  B0530WS7F IC  pkg SOD323XB  page 115 : 1 = PWRGD_FAIL_CPU1_EF_R1 ; 2 = P3V3_AUX
D49  SCHOTTKY_12  B0530WS7F IC  pkg SOD323XB  page 115 : 1 = PWRGD_FAIL_CPU1_GH_R1 ; 2 = P3V3_AUX
D65  Q_LED  IC  pkg SMLF  page 256 : A = LED_RST_PLD_CPU0_DRAM_AB_N ; C = LED_RST_PLD_CPU0_DRAM_AB_N_D
D66  Q_LED  IC  pkg SMLF  page 256 : A = LED_RST_PLD_CPU0_DRAM_CD_N ; C = LED_RST_PLD_CPU0_DRAM_CD_N_D
D67  Q_LED  IC  pkg SMLF  page 256 : A = LED_RST_PLD_CPU0_DRAM_EF_N ; C = LED_RST_PLD_CPU0_DRAM_EF_N_D
D68  Q_LED  IC  pkg SMLF  page 256 : A = LED_RST_PLD_CPU0_DRAM_GH_N ; C = LED_RST_PLD_CPU0_DRAM_GH_N_D
D69  Q_LED  IC  pkg SMLF  page 256 : A = LED_RST_PLD_CPU1_DRAM_AB_N ; C = LED_RST_PLD_CPU1_DRAM_AB_N_D
D70  Q_LED  IC  pkg SMLF  page 256 : A = LED_RST_PLD_CPU1_DRAM_CD_N ; C = LED_RST_PLD_CPU1_DRAM_CD_N_D
D71  Q_LED  IC  pkg SMLF  page 256 : A = LED_RST_PLD_CPU1_DRAM_EF_N ; C = LED_RST_PLD_CPU1_DRAM_EF_N_D
D72  Q_LED  IC  pkg SMLF  page 256 : A = LED_RST_PLD_CPU1_DRAM_GH_N ; C = LED_RST_PLD_CPU1_DRAM_GH_N_D
D73  Q_LED  IC  pkg SMLF  page 253 : A = LED_PWRGD_PVCCD_HV_CPU0 ; C = LED_PWRGD_PVCCD_HV_CPU0_D
D74  Q_LED  IC  pkg SMLF  page 253 : A = LED_PWRGD_PVPP_HBM_CPU0 ; C = LED_PWRGD_PVPP_HBM_CPU0_D
D75  Q_LED  IC  pkg SMLF  page 253 : A = LED_PWRGD_PVCCFA_EHV_CPU0 ; C = LED_PWRGD_PVCCFA_EHV_CPU0_D
D76  Q_LED  IC  pkg SMLF  page 253 : A = LED_PWRGD_PVCCFA_EHV_FIVRA_CPU0 ; C = LED_PWRGD_PVCCFA_EHV_FIVRA_CP_1
D77  Q_LED  IC  pkg SMLF  page 253 : A = LED_PWRGD_PVCCINFAON_CPU0 ; C = LED_PWRGD_PVCCINFAON_CPU0_D
D78  Q_LED  IC  pkg SMLF  page 253 : A = LED_PWRGD_PVNN_MAIN_CPU0 ; C = LED_PWRGD_PVNN_MAIN_CPU0_D
